# T6G (Grand Teton) — schematic netlist excerpt (pin names and nets, part order shuffled) for the footprints in the layout excerpt that follows; sources: Cadence DE-HDL packaged netlist, KiCad conversion of 04192023_DAF0TMB3IC0_F0TG_MB_C_brd_V02_OCP.brd

R3307  Q_RES  0 5% CHIP  pkg 0402LF  page 143 : A = OCP_SFF_RBT_ARB_IN_MUX2 ; B = OCP_SFF_RBT_ARB_IN_MUX2_R
H49  HOLE  EMPTY  pkg TH  page 230 : \1\ = GND
R6047  Q_RES  0 5% CHIP  pkg 0402LF  page 81 : A = PWRGD_P3V3_AUX ; B = PWRGD_P3V3_AUX_R

(kicad_pcb
	(version 20260206)
	(generator "pcbnew")
	(generator_version "10.0")
	(general
		(thickness 1.6)
		(legacy_teardrops no)
	)
	(paper "A4")
	(title_block
		(title "04192023_DAF0TMB3IC0_F0TG_MB_C_brd_V02_OCP.brd")
		(comment 1 "Grand Teton / footprints 2598-2600 of 8354")
	)
	(layers
		(0 "F.Cu" signal "TOP")
		(4 "In1.Cu" signal "GND")
		(6 "In2.Cu" signal "IN1")
		(8 "In3.Cu" signal "GND1")
		(10 "In4.Cu" signal "IN2")
		(12 "In5.Cu" signal "GND2")
		(14 "In6.Cu" signal "IN3")
		(16 "In7.Cu" signal "GND3")
		(18 "In8.Cu" signal "VCC")
		(20 "In9.Cu" signal "VCC1")
		(22 "In10.Cu" signal "GND4")
		(24 "In11.Cu" signal "IN4")
		(26 "In12.Cu" signal "GND5")
		(28 "In13.Cu" signal "IN5")
		(30 "In14.Cu" signal "GND6")
		(32 "In15.Cu" signal "IN6")
		(34 "In16.Cu" signal "GND7")
		(2 "B.Cu" signal "BOTTOM")
		(9 "F.Adhes" user "F.Adhesive")
		(11 "B.Adhes" user "B.Adhesive")
		(13 "F.Paste" user "Package Geometry/Pastemask Top")
		(15 "B.Paste" user "Package Geometry/Pastemask Bottom")
		(5 "F.SilkS" user "Ref Des/Silkscreen Top")
		(7 "B.SilkS" user "Ref Des/Silkscreen Bottom")
		(1 "F.Mask" user "Board Geometry/Soldermask Top")
		(3 "B.Mask" user "Board Geometry/Soldermask Bottom")
		(17 "Dwgs.User" user "User.Drawings")
		(19 "Cmts.User" user "User.Comments")
		(21 "Eco1.User" user "User.Eco1")
		(23 "Eco2.User" user "User.Eco2")
		(25 "Edge.Cuts" user "Board Geometry/Outline")
		(27 "Margin" user)
		(31 "F.CrtYd" user "Package Geometry/Place Bound Top")
		(29 "B.CrtYd" user "Package Geometry/Place Bound Bottom")
		(35 "F.Fab" user "Ref Des/Assembly Top")
		(33 "B.Fab" user "Ref Des/Assembly Bottom")
	)
	(footprint ""
		(layer "F.Cu")
		(at 200.939908 -109.561376 180)
		(property "Reference" "R6047"
			(at 0 0 180)
			(layer "F.SilkS")
			(hide yes)
			(effects
				(font
					(size 1.27 1.27)
				)
			)
		)
		(property "Value" ""
			(at 0 0 180)
			(layer "F.Fab")
			(effects
				(font
					(size 1.27 1.27)
				)
			)
		)
		(duplicate_pad_numbers_are_jumpers no)
		(fp_line
			(start 0.7874 0.4064)
			(end -0.7874 0.4064)
			(stroke
				(width 0.1524)
				(type default)
			)
			(layer "F.SilkS")
		)
		(fp_line
			(start 0.7874 -0.4064)
			(end 0.7874 0.4064)
			(stroke
				(width 0.1524)
				(type default)
			)
			(layer "F.SilkS")
		)
		(fp_line
			(start -0.7874 0.4064)
			(end -0.7874 -0.4064)
			(stroke
				(width 0.1524)
				(type default)
			)
			(layer "F.SilkS")
		)
		(fp_line
			(start -0.7874 -0.4064)
			(end 0.7874 -0.4064)
			(stroke
				(width 0.1524)
				(type default)
			)
			(layer "F.SilkS")
		)
		(fp_line
			(start 0.67945 0.3048)
			(end 0.120396 0.3048)
			(stroke
				(width 0.1)
				(type default)
			)
			(layer "F.Fab")
		)
		(fp_line
			(start 0.67945 -0.3048)
			(end 0.67945 0.3048)
			(stroke
				(width 0.1)
				(type default)
			)
			(layer "F.Fab")
		)
		(fp_line
			(start 0.12065 -0.2794)
			(end 0.12065 -0.3048)
			(stroke
				(width 0.1)
				(type default)
			)
			(layer "F.Fab")
		)
		(fp_line
			(start 0.12065 -0.3048)
			(end 0.67945 -0.3048)
			(stroke
				(width 0.1)
				(type default)
			)
			(layer "F.Fab")
		)
		(fp_line
			(start 0.120396 0.3048)
			(end 0.120396 0.2794)
			(stroke
				(width 0.1)
				(type default)
			)
			(layer "F.Fab")
		)
		(fp_line
			(start 0.120396 0.2794)
			(end -0.12065 0.2794)
			(stroke
				(width 0.1)
				(type default)
			)
			(layer "F.Fab")
		)
		(fp_line
			(start -0.12065 0.3048)
			(end -0.67945 0.3048)
			(stroke
				(width 0.1)
				(type default)
			)
			(layer "F.Fab")
		)
		(fp_line
			(start -0.12065 0.2794)
			(end -0.12065 0.3048)
			(stroke
				(width 0.1)
				(type default)
			)
			(layer "F.Fab")
		)
		(fp_line
			(start -0.12065 -0.2794)
			(end 0.12065 -0.2794)
			(stroke
				(width 0.1)
				(type default)
			)
			(layer "F.Fab")
		)
		(fp_line
			(start -0.12065 -0.305054)
			(end -0.12065 -0.2794)
			(stroke
				(width 0.1)
				(type default)
			)
			(layer "F.Fab")
		)
		(fp_line
			(start -0.67945 0.3048)
			(end -0.67945 -0.305054)
			(stroke
				(width 0.1)
				(type default)
			)
			(layer "F.Fab")
		)
		(fp_line
			(start -0.67945 -0.305054)
			(end -0.12065 -0.305054)
			(stroke
				(width 0.1)
				(type default)
			)
			(layer "F.Fab")
		)
		(pad "1" smd circle
			(at -0.40005 0 180)
			(size 0 0)
			(layers "F.Cu" "F.Mask" "F.Paste")
			(net "PWRGD_P3V3_AUX")
		)
		(pad "2" smd circle
			(at 0.40005 0 180)
			(size 0 0)
			(layers "F.Cu" "F.Mask" "F.Paste")
			(net "PWRGD_P3V3_AUX_R")
		)
	)
	(footprint ""
		(layer "F.Cu")
		(at 201.086212 -351.825052)
		(property "Reference" "H49"
			(at -3.0226 -3.96113 0)
			(unlocked yes)
			(layer "F.SilkS")
			(effects
				(font
					(size 0.7874 0.5842)
					(thickness 0.1524)
				)
				(justify left)
			)
		)
		(property "Value" ""
			(at 0 0 0)
			(layer "F.Fab")
			(effects
				(font
					(size 1.27 1.27)
				)
			)
		)
		(duplicate_pad_numbers_are_jumpers no)
		(pad "1" thru_hole circle
			(at 0 0)
			(size 6.1976 6.1976)
			(drill 3.7338)
			(layers "*.Cu" "*.Mask")
			(remove_unused_layers no)
			(net "GND")
			(clearance -0.9779)
			(padstack
				(mode front_inner_back)
				(layer "Inner"
					(shape circle)
					(size 5.5372 5.5372)
					(clearance -0.6477)
				)
				(layer "B.Cu"
					(shape circle)
					(size 6.1976 6.1976)
					(clearance -0.9779)
				)
			)
		)
	)
	(footprint ""
		(layer "F.Cu")
		(at 147.69084 -93.174058 180)
		(property "Reference" "R3307"
			(at 0 0 180)
			(layer "F.SilkS")
			(hide yes)
			(effects
				(font
					(size 1.27 1.27)
				)
			)
		)
		(property "Value" ""
			(at 0 0 180)
			(layer "F.Fab")
			(effects
				(font
					(size 1.27 1.27)
				)
			)
		)
		(duplicate_pad_numbers_are_jumpers no)
		(fp_line
			(start 0.7874 0.4064)
			(end -0.7874 0.4064)
			(stroke
				(width 0.1524)
				(type default)
			)
			(layer "F.SilkS")
		)
		(fp_line
			(start 0.7874 -0.4064)
			(end 0.7874 0.4064)
			(stroke
				(width 0.1524)
				(type default)
			)
			(layer "F.SilkS")
		)
		(fp_line
			(start -0.7874 0.4064)
			(end -0.7874 -0.4064)
			(stroke
				(width 0.1524)
				(type default)
			)
			(layer "F.SilkS")
		)
		(fp_line
			(start -0.7874 -0.4064)
			(end 0.7874 -0.4064)
			(stroke
				(width 0.1524)
				(type default)
			)
			(layer "F.SilkS")
		)
		(fp_line
			(start 0.67945 0.3048)
			(end 0.120396 0.3048)
			(stroke
				(width 0.1)
				(type default)
			)
			(layer "F.Fab")
		)
		(fp_line
			(start 0.67945 -0.3048)
			(end 0.67945 0.3048)
			(stroke
				(width 0.1)
				(type default)
			)
			(layer "F.Fab")
		)
		(fp_line
			(start 0.12065 -0.2794)
			(end 0.12065 -0.3048)
			(stroke
				(width 0.1)
				(type default)
			)
			(layer "F.Fab")
		)
		(fp_line
			(start 0.12065 -0.3048)
			(end 0.67945 -0.3048)
			(stroke
				(width 0.1)
				(type default)
			)
			(layer "F.Fab")
		)
		(fp_line
			(start 0.120396 0.3048)
			(end 0.120396 0.2794)
			(stroke
				(width 0.1)
				(type default)
			)
			(layer "F.Fab")
		)
		(fp_line
			(start 0.120396 0.2794)
			(end -0.12065 0.2794)
			(stroke
				(width 0.1)
				(type default)
			)
			(layer "F.Fab")
		)
		(fp_line
			(start -0.12065 0.3048)
			(end -0.67945 0.3048)
			(stroke
				(width 0.1)
				(type default)
			)
			(layer "F.Fab")
		)
		(fp_line
			(start -0.12065 0.2794)
			(end -0.12065 0.3048)
			(stroke
				(width 0.1)
				(type default)
			)
			(layer "F.Fab")
		)
		(fp_line
			(start -0.12065 -0.2794)
			(end 0.12065 -0.2794)
			(stroke
				(width 0.1)
				(type default)
			)
			(layer "F.Fab")
		)
		(fp_line
			(start -0.12065 -0.305054)
			(end -0.12065 -0.2794)
			(stroke
				(width 0.1)
				(type default)
			)
			(layer "F.Fab")
		)
		(fp_line
			(start -0.67945 0.3048)
			(end -0.67945 -0.305054)
			(stroke
				(width 0.1)
				(type default)
			)
			(layer "F.Fab")
		)
		(fp_line
			(start -0.67945 -0.305054)
			(end -0.12065 -0.305054)
			(stroke
				(width 0.1)
				(type default)
			)
			(layer "F.Fab")
		)
		(pad "1" smd circle
			(at -0.40005 0 180)
			(size 0 0)
			(layers "F.Cu" "F.Mask" "F.Paste")
			(net "OCP_SFF_RBT_ARB_IN_MUX2")
		)
		(pad "2" smd circle
			(at 0.40005 0 180)
			(size 0 0)
			(layers "F.Cu" "F.Mask" "F.Paste")
			(net "OCP_SFF_RBT_ARB_IN_MUX2_R")
		)
	)
)
